(kicad_pcb
	(version 20260206)
	(generator "pcbnew")
	(generator_version "10.0")
	(general
		(thickness 1.6)
		(legacy_teardrops no)
	)
	(paper "A4")
	(title_block
		(title "04192023_DAF0TMB3IC0_F0TG_MB_C_brd_V02_OCP.brd")
		(comment 1 "Grand Teton / footprints 4423-4427 of 8354")
	)
	(layers
		(0 "F.Cu" signal "TOP")
		(4 "In1.Cu" signal "GND")
		(6 "In2.Cu" signal "IN1")
		(8 "In3.Cu" signal "GND1")
		(10 "In4.Cu" signal "IN2")
		(12 "In5.Cu" signal "GND2")
		(14 "In6.Cu" signal "IN3")
		(16 "In7.Cu" signal "GND3")
		(18 "In8.Cu" signal "VCC")
		(20 "In9.Cu" signal "VCC1")
		(22 "In10.Cu" signal "GND4")
		(24 "In11.Cu" signal "IN4")
		(26 "In12.Cu" signal "GND5")
		(28 "In13.Cu" signal "IN5")
		(30 "In14.Cu" signal "GND6")
		(32 "In15.Cu" signal "IN6")
		(34 "In16.Cu" signal "GND7")
		(2 "B.Cu" signal "BOTTOM")
		(9 "F.Adhes" user "F.Adhesive")
		(11 "B.Adhes" user "B.Adhesive")
		(13 "F.Paste" user "Package Geometry/Pastemask Top")
		(15 "B.Paste" user "Package Geometry/Pastemask Bottom")
		(5 "F.SilkS" user "Ref Des/Silkscreen Top")
		(7 "B.SilkS" user "Ref Des/Silkscreen Bottom")
		(1 "F.Mask" user "Board Geometry/Soldermask Top")
		(3 "B.Mask" user "Board Geometry/Soldermask Bottom")
		(17 "Dwgs.User" user "User.Drawings")
		(19 "Cmts.User" user "User.Comments")
		(21 "Eco1.User" user "User.Eco1")
		(23 "Eco2.User" user "User.Eco2")
		(25 "Edge.Cuts" user "Board Geometry/Outline")
		(27 "Margin" user)
		(31 "F.CrtYd" user "Package Geometry/Place Bound Top")
		(29 "B.CrtYd" user "Package Geometry/Place Bound Bottom")
		(35 "F.Fab" user "Ref Des/Assembly Top")
		(33 "B.Fab" user "Ref Des/Assembly Bottom")
	)
	(footprint ""
		(layer "F.Cu")
		(at 102.154736 -127.787654 90)
		(property "Reference" "R1443"
			(at 0 0 90)
			(layer "F.SilkS")
			(hide yes)
			(effects
				(font
					(size 1.27 1.27)
				)
			)
		)
		(property "Value" ""
			(at 0 0 90)
			(layer "F.Fab")
			(effects
				(font
					(size 1.27 1.27)
				)
			)
		)
		(duplicate_pad_numbers_are_jumpers no)
		(fp_line
			(start 0.7874 -0.4064)
			(end 0.7874 0.4064)
			(stroke
				(width 0.1524)
				(type default)
			)
			(layer "F.SilkS")
		)
		(fp_line
			(start -0.7874 -0.4064)
			(end 0.7874 -0.4064)
			(stroke
				(width 0.1524)
				(type default)
			)
			(layer "F.SilkS")
		)
		(fp_line
			(start 0.7874 0.4064)
			(end -0.7874 0.4064)
			(stroke
				(width 0.1524)
				(type default)
			)
			(layer "F.SilkS")
		)
		(fp_line
			(start -0.7874 0.4064)
			(end -0.7874 -0.4064)
			(stroke
				(width 0.1524)
				(type default)
			)
			(layer "F.SilkS")
		)
		(fp_line
			(start -0.12065 -0.305054)
			(end -0.12065 -0.2794)
			(stroke
				(width 0.1)
				(type default)
			)
			(layer "F.Fab")
		)
		(fp_line
			(start -0.67945 -0.305054)
			(end -0.12065 -0.305054)
			(stroke
				(width 0.1)
				(type default)
			)
			(layer "F.Fab")
		)
		(fp_line
			(start 0.67945 -0.3048)
			(end 0.67945 0.3048)
			(stroke
				(width 0.1)
				(type default)
			)
			(layer "F.Fab")
		)
		(fp_line
			(start 0.12065 -0.3048)
			(end 0.67945 -0.3048)
			(stroke
				(width 0.1)
				(type default)
			)
			(layer "F.Fab")
		)
		(fp_line
			(start 0.12065 -0.2794)
			(end 0.12065 -0.3048)
			(stroke
				(width 0.1)
				(type default)
			)
			(layer "F.Fab")
		)
		(fp_line
			(start -0.12065 -0.2794)
			(end 0.12065 -0.2794)
			(stroke
				(width 0.1)
				(type default)
			)
			(layer "F.Fab")
		)
		(fp_line
			(start 0.120396 0.2794)
			(end -0.12065 0.2794)
			(stroke
				(width 0.1)
				(type default)
			)
			(layer "F.Fab")
		)
		(fp_line
			(start -0.12065 0.2794)
			(end -0.12065 0.3048)
			(stroke
				(width 0.1)
				(type default)
			)
			(layer "F.Fab")
		)
		(fp_line
			(start 0.67945 0.3048)
			(end 0.120396 0.3048)
			(stroke
				(width 0.1)
				(type default)
			)
			(layer "F.Fab")
		)
		(fp_line
			(start 0.120396 0.3048)
			(end 0.120396 0.2794)
			(stroke
				(width 0.1)
				(type default)
			)
			(layer "F.Fab")
		)
		(fp_line
			(start -0.12065 0.3048)
			(end -0.67945 0.3048)
			(stroke
				(width 0.1)
				(type default)
			)
			(layer "F.Fab")
		)
		(fp_line
			(start -0.67945 0.3048)
			(end -0.67945 -0.305054)
			(stroke
				(width 0.1)
				(type default)
			)
			(layer "F.Fab")
		)
		(pad "1" smd circle
			(at -0.40005 0 90)
			(size 0 0)
			(layers "F.Cu" "F.Mask" "F.Paste")
			(net "PWRGD_P12V_MEM_CPU0_EN")
		)
		(pad "2" smd circle
			(at 0.40005 0 90)
			(size 0 0)
			(layers "F.Cu" "F.Mask" "F.Paste")
			(net "GND")
		)
	)
	(footprint ""
		(layer "F.Cu")
		(at 406.147778 -168.59377 180)
		(property "Reference" "PU50"
			(at 5.635752 -4.803394 0)
			(unlocked yes)
			(layer "F.SilkS")
			(effects
				(font
					(size 0.7874 0.5842)
					(thickness 0.1524)
				)
				(justify left)
			)
		)
		(property "Value" ""
			(at 0 0 180)
			(layer "F.Fab")
			(effects
				(font
					(size 1.27 1.27)
				)
			)
		)
		(duplicate_pad_numbers_are_jumpers no)
		(fp_line
			(start 2.500122 2.999994)
			(end 2.2987 2.999994)
			(stroke
				(width 0.1524)
				(type default)
			)
			(layer "F.SilkS")
		)
		(fp_line
			(start 2.500122 2.339594)
			(end 2.500122 2.999994)
			(stroke
				(width 0.1524)
				(type default)
			)
			(layer "F.SilkS")
		)
		(fp_line
			(start 2.500122 -2.999994)
			(end 2.500122 -2.44348)
			(stroke
				(width 0.1524)
				(type default)
			)
			(layer "F.SilkS")
		)
		(fp_line
			(start 2.31394 -2.999994)
			(end 2.500122 -2.999994)
			(stroke
				(width 0.1524)
				(type default)
			)
			(layer "F.SilkS")
		)
		(fp_line
			(start -2.2987 2.999994)
			(end -2.500122 2.999994)
			(stroke
				(width 0.1524)
				(type default)
			)
			(layer "F.SilkS")
		)
		(fp_line
			(start -2.500122 2.999994)
			(end -2.500122 2.339594)
			(stroke
				(width 0.1524)
				(type default)
			)
			(layer "F.SilkS")
		)
		(fp_line
			(start -2.500122 0.6604)
			(end -2.500122 0.229108)
			(stroke
				(width 0.1524)
				(type default)
			)
			(layer "F.SilkS")
		)
		(fp_line
			(start -2.500122 -2.529078)
			(end -2.500122 -2.999994)
			(stroke
				(width 0.1524)
				(type default)
			)
			(layer "F.SilkS")
		)
		(fp_line
			(start -2.500122 -2.999994)
			(end -2.24409 -2.999994)
			(stroke
				(width 0.1524)
				(type default)
			)
			(layer "F.SilkS")
		)
		(fp_poly
			(pts
				(xy -2.758948 -2.425192) (xy -3.526028 -2.680716) (xy -3.014472 -3.192272)
			)
			(stroke
				(width 0)
				(type default)
			)
			(fill yes)
			(layer "F.SilkS")
		)
		(fp_line
			(start 2.500122 2.999994)
			(end -2.500122 2.999994)
			(stroke
				(width 0.1)
				(type default)
			)
			(layer "F.Fab")
		)
		(fp_line
			(start 2.500122 -2.999994)
			(end 2.500122 2.999994)
			(stroke
				(width 0.1)
				(type default)
			)
			(layer "F.Fab")
		)
		(fp_line
			(start -2.500122 2.999994)
			(end -2.500122 -2.999994)
			(stroke
				(width 0.1)
				(type default)
			)
			(layer "F.Fab")
		)
		(fp_line
			(start -2.500122 -2.999994)
			(end 2.500122 -2.999994)
			(stroke
				(width 0.1)
				(type default)
			)
			(layer "F.Fab")
		)
		(fp_poly
			(pts
				(xy -4.218432 -2.783078) (xy -4.218432 -1.767078) (xy -3.202432 -2.275078)
			)
			(stroke
				(width 0)
				(type default)
			)
			(fill yes)
			(layer "F.Fab")
		)
		(pad "1" smd rect
			(at -2.400046 -2.275078 270)
			(size 0.2286 0.6096)
			(layers "F.Cu" "F.Mask" "F.Paste")
			(net "PVDDCR_SOC_P0_VOS2")
		)
		(pad "2" smd rect
			(at -2.400046 -1.82499 270)
			(size 0.2286 0.6096)
			(layers "F.Cu" "F.Mask" "F.Paste")
			(net "GND")
		)
		(pad "3" smd rect
			(at -2.400046 -1.374902 270)
			(size 0.2286 0.6096)
			(layers "F.Cu" "F.Mask" "F.Paste")
			(net "PVDDCR_SOC_P0_VCC2")
		)
		(pad "4" smd rect
			(at -2.400046 -0.925068 270)
			(size 0.2286 0.6096)
			(layers "F.Cu" "F.Mask" "F.Paste")
			(net "PVDDCR_CPU0_P0_PVCC")
		)
		(pad "5" smd rect
			(at -2.400046 -0.47498 270)
			(size 0.2286 0.6096)
			(layers "F.Cu" "F.Mask" "F.Paste")
			(net "GND")
		)
		(pad "6" smd rect
			(at -2.400046 -0.024892 270)
			(size 0.2286 0.6096)
			(layers "F.Cu" "F.Mask" "F.Paste")
			(net "NC_PVDDCR_SOC_P0_GL1_2")
		)
		(pad "7_9-20_24" smd circle
			(at 0 1.150112 270)
			(size 0 0)
			(layers "F.Cu" "F.Mask" "F.Paste")
			(net "GND")
		)
		(pad "10_19" smd rect
			(at 0 2.899918 270)
			(size 0.6096 4.318)
			(layers "F.Cu" "F.Mask" "F.Paste")
			(net "SW_PVDDCR_SOC_P0_SW2")
		)
		(pad "25_29" smd rect
			(at 1.549908 -1.279906 90)
			(size 2.0574 2.3114)
			(layers "F.Cu" "F.Mask" "F.Paste")
			(net "SW_P12V_AUX_PVDDCR_SOC_P0_FLT")
		)
		(pad "30" smd rect
			(at 2.05994 -2.899918 180)
			(size 0.2286 0.6096)
			(layers "F.Cu" "F.Mask" "F.Paste")
			(net "SW_P12V_AUX_PVDDCR_SOC_P0_FLT")
		)
		(pad "31" smd rect
			(at 1.610106 -2.899918 180)
			(size 0.2286 0.6096)
			(layers "F.Cu" "F.Mask" "F.Paste")
			(net "NC_PVDDCR_SOC_P0_DNC2")
		)
		(pad "32" smd rect
			(at 1.160018 -2.899918 180)
			(size 0.2286 0.6096)
			(layers "F.Cu" "F.Mask" "F.Paste")
			(net "SW_PVDDCR_SOC_P0_PH2")
		)
		(pad "33" smd rect
			(at 0.70993 -2.899918 180)
			(size 0.2286 0.6096)
			(layers "F.Cu" "F.Mask" "F.Paste")
			(net "SW_PVDDCR_SOC_P0_BOOT2")
		)
		(pad "34" smd rect
			(at 0.260096 -2.899918 180)
			(size 0.2286 0.6096)
			(layers "F.Cu" "F.Mask" "F.Paste")
			(net "PVDDCR_SOC_P0_PWM2")
		)
		(pad "35" smd rect
			(at -0.189992 -2.899918 180)
			(size 0.2286 0.6096)
			(layers "F.Cu" "F.Mask" "F.Paste")
			(net "PVDDCR_SOC_P0_VCC2")
		)
		(pad "36" smd rect
			(at -0.64008 -2.899918 180)
			(size 0.2286 0.6096)
			(layers "F.Cu" "F.Mask" "F.Paste")
			(net "PVDDCR_SOC_P0_TEMP1")
		)
		(pad "37" smd rect
			(at -1.089914 -2.899918 180)
			(size 0.2286 0.6096)
			(layers "F.Cu" "F.Mask" "F.Paste")
			(net "PVDDCR_SOC_P0_LSET2")
		)
		(pad "38" smd rect
			(at -1.540002 -2.899918 180)
			(size 0.2286 0.6096)
			(layers "F.Cu" "F.Mask" "F.Paste")
			(net "PVDDCR_SOC_P0_IMON2")
		)
		(pad "39" smd rect
			(at -1.99009 -2.899918 180)
			(size 0.2286 0.6096)
			(layers "F.Cu" "F.Mask" "F.Paste")
			(net "PVDDCR_CPU0_P0_VCCS")
		)
		(pad "40" smd rect
			(at -0.87503 -1.27508 180)
			(size 1.7526 1.9558)
			(layers "F.Cu" "F.Mask" "F.Paste")
			(net "GND")
		)
		(pad "41" smd rect
			(at -1.525016 0.249936 90)
			(size 0.3048 0.4572)
			(layers "F.Cu" "F.Mask" "F.Paste")
			(net "NC_PVDDCR_SOC_P0_GL2_2")
		)
		(zone
			(layer "F.Cu")
			(hatch none 0.5)
			(connect_pads
				(clearance 0)
			)
			(min_thickness 0.25)
			(keepout
				(tracks not_allowed)
				(vias allowed)
				(pads allowed)
				(copperpour not_allowed)
				(footprints allowed)
			)
			(placement
				(enabled no)
				(sheetname "")
			)
			(fill
				(thermal_gap 0.5)
				(thermal_bridge_width 0.5)
				(island_removal_mode 0)
			)
			(polygon
				(pts
					(xy 408.6479 -171.186856) (xy 408.6479 -170.844464) (xy 403.647656 -170.844464) (xy 403.647656 -171.175934)
					(xy 403.937978 -171.175934) (xy 403.937978 -171.138088) (xy 408.357578 -171.138088) (xy 408.357578 -171.186856)
				)
			)
		)
		(zone
			(layer "F.Cu")
			(hatch none 0.5)
			(connect_pads
				(clearance 0)
			)
			(min_thickness 0.25)
			(keepout
				(tracks not_allowed)
				(vias allowed)
				(pads allowed)
				(copperpour not_allowed)
				(footprints allowed)
			)
			(placement
				(enabled no)
				(sheetname "")
			)
			(fill
				(thermal_gap 0.5)
				(thermal_bridge_width 0.5)
				(island_removal_mode 0)
			)
			(polygon
				(pts
					(xy 406.095708 -168.34739) (xy 406.095708 -166.28999) (xy 407.949908 -166.28999) (xy 407.949908 -166.531036)
					(xy 408.192224 -166.531036) (xy 408.192224 -166.049452) (xy 404.298658 -166.049452) (xy 404.298658 -166.234364)
					(xy 405.80437 -166.234364) (xy 405.80437 -168.393364) (xy 403.647656 -168.393364) (xy 403.647656 -168.643046)
					(xy 405.800052 -168.643046)
				)
			)
		)
	)
	(footprint ""
		(layer "F.Cu")
		(at 33.81248 -368.467132 90)
		(property "Reference" "PC93"
			(at 0 0 90)
			(layer "F.SilkS")
			(hide yes)
			(effects
				(font
					(size 1.27 1.27)
				)
			)
		)
		(property "Value" ""
			(at 0 0 90)
			(layer "F.Fab")
			(effects
				(font
					(size 1.27 1.27)
				)
			)
		)
		(duplicate_pad_numbers_are_jumpers no)
		(fp_line
			(start 0.7874 -0.4064)
			(end 0.7874 0.4064)
			(stroke
				(width 0.1524)
				(type default)
			)
			(layer "F.SilkS")
		)
		(fp_line
			(start -0.7874 -0.4064)
			(end 0.7874 -0.4064)
			(stroke
				(width 0.1524)
				(type default)
			)
			(layer "F.SilkS")
		)
		(fp_line
			(start 0.7874 0.4064)
			(end -0.7874 0.4064)
			(stroke
				(width 0.1524)
				(type default)
			)
			(layer "F.SilkS")
		)
		(fp_line
			(start -0.7874 0.4064)
			(end -0.7874 -0.4064)
			(stroke
				(width 0.1524)
				(type default)
			)
			(layer "F.SilkS")
		)
		(fp_line
			(start -0.12065 -0.305054)
			(end -0.12065 -0.2794)
			(stroke
				(width 0.1)
				(type default)
			)
			(layer "F.Fab")
		)
		(fp_line
			(start -0.67945 -0.305054)
			(end -0.12065 -0.305054)
			(stroke
				(width 0.1)
				(type default)
			)
			(layer "F.Fab")
		)
		(fp_line
			(start 0.67945 -0.3048)
			(end 0.67945 0.3048)
			(stroke
				(width 0.1)
				(type default)
			)
			(layer "F.Fab")
		)
		(fp_line
			(start 0.12065 -0.3048)
			(end 0.67945 -0.3048)
			(stroke
				(width 0.1)
				(type default)
			)
			(layer "F.Fab")
		)
		(fp_line
			(start 0.12065 -0.2794)
			(end 0.12065 -0.3048)
			(stroke
				(width 0.1)
				(type default)
			)
			(layer "F.Fab")
		)
		(fp_line
			(start -0.12065 -0.2794)
			(end 0.12065 -0.2794)
			(stroke
				(width 0.1)
				(type default)
			)
			(layer "F.Fab")
		)
		(fp_line
			(start 0.120396 0.2794)
			(end -0.12065 0.2794)
			(stroke
				(width 0.1)
				(type default)
			)
			(layer "F.Fab")
		)
		(fp_line
			(start -0.12065 0.2794)
			(end -0.12065 0.3048)
			(stroke
				(width 0.1)
				(type default)
			)
			(layer "F.Fab")
		)
		(fp_line
			(start 0.67945 0.3048)
			(end 0.120396 0.3048)
			(stroke
				(width 0.1)
				(type default)
			)
			(layer "F.Fab")
		)
		(fp_line
			(start 0.120396 0.3048)
			(end 0.120396 0.2794)
			(stroke
				(width 0.1)
				(type default)
			)
			(layer "F.Fab")
		)
		(fp_line
			(start -0.12065 0.3048)
			(end -0.67945 0.3048)
			(stroke
				(width 0.1)
				(type default)
			)
			(layer "F.Fab")
		)
		(fp_line
			(start -0.67945 0.3048)
			(end -0.67945 -0.305054)
			(stroke
				(width 0.1)
				(type default)
			)
			(layer "F.Fab")
		)
		(pad "1" smd circle
			(at -0.40005 0 90)
			(size 0 0)
			(layers "F.Cu" "F.Mask" "F.Paste")
			(net "PVDDCR_CPU1_P1_VCCS")
		)
		(pad "2" smd circle
			(at 0.40005 0 90)
			(size 0 0)
			(layers "F.Cu" "F.Mask" "F.Paste")
			(net "GND")
		)
	)
	(footprint ""
		(layer "F.Cu")
		(at 173.597062 -32.935672 90)
		(property "Reference" "PR4005"
			(at 0 0 90)
			(layer "F.SilkS")
			(hide yes)
			(effects
				(font
					(size 1.27 1.27)
				)
			)
		)
		(property "Value" ""
			(at 0 0 90)
			(layer "F.Fab")
			(effects
				(font
					(size 1.27 1.27)
				)
			)
		)
		(duplicate_pad_numbers_are_jumpers no)
		(fp_line
			(start 0.7874 -0.4064)
			(end 0.7874 0.4064)
			(stroke
				(width 0.1524)
				(type default)
			)
			(layer "F.SilkS")
		)
		(fp_line
			(start -0.7874 -0.4064)
			(end 0.7874 -0.4064)
			(stroke
				(width 0.1524)
				(type default)
			)
			(layer "F.SilkS")
		)
		(fp_line
			(start 0.7874 0.4064)
			(end -0.7874 0.4064)
			(stroke
				(width 0.1524)
				(type default)
			)
			(layer "F.SilkS")
		)
		(fp_line
			(start -0.7874 0.4064)
			(end -0.7874 -0.4064)
			(stroke
				(width 0.1524)
				(type default)
			)
			(layer "F.SilkS")
		)
		(fp_line
			(start -0.12065 -0.305054)
			(end -0.12065 -0.2794)
			(stroke
				(width 0.1)
				(type default)
			)
			(layer "F.Fab")
		)
		(fp_line
			(start -0.67945 -0.305054)
			(end -0.12065 -0.305054)
			(stroke
				(width 0.1)
				(type default)
			)
			(layer "F.Fab")
		)
		(fp_line
			(start 0.67945 -0.3048)
			(end 0.67945 0.3048)
			(stroke
				(width 0.1)
				(type default)
			)
			(layer "F.Fab")
		)
		(fp_line
			(start 0.12065 -0.3048)
			(end 0.67945 -0.3048)
			(stroke
				(width 0.1)
				(type default)
			)
			(layer "F.Fab")
		)
		(fp_line
			(start 0.12065 -0.2794)
			(end 0.12065 -0.3048)
			(stroke
				(width 0.1)
				(type default)
			)
			(layer "F.Fab")
		)
		(fp_line
			(start -0.12065 -0.2794)
			(end 0.12065 -0.2794)
			(stroke
				(width 0.1)
				(type default)
			)
			(layer "F.Fab")
		)
		(fp_line
			(start 0.120396 0.2794)
			(end -0.12065 0.2794)
			(stroke
				(width 0.1)
				(type default)
			)
			(layer "F.Fab")
		)
		(fp_line
			(start -0.12065 0.2794)
			(end -0.12065 0.3048)
			(stroke
				(width 0.1)
				(type default)
			)
			(layer "F.Fab")
		)
		(fp_line
			(start 0.67945 0.3048)
			(end 0.120396 0.3048)
			(stroke
				(width 0.1)
				(type default)
			)
			(layer "F.Fab")
		)
		(fp_line
			(start 0.120396 0.3048)
			(end 0.120396 0.2794)
			(stroke
				(width 0.1)
				(type default)
			)
			(layer "F.Fab")
		)
		(fp_line
			(start -0.12065 0.3048)
			(end -0.67945 0.3048)
			(stroke
				(width 0.1)
				(type default)
			)
			(layer "F.Fab")
		)
		(fp_line
			(start -0.67945 0.3048)
			(end -0.67945 -0.305054)
			(stroke
				(width 0.1)
				(type default)
			)
			(layer "F.Fab")
		)
		(pad "1" smd circle
			(at -0.40005 0 90)
			(size 0 0)
			(layers "F.Cu" "F.Mask" "F.Paste")
			(net "P12V_SCM_IMON")
		)
		(pad "2" smd circle
			(at 0.40005 0 90)
			(size 0 0)
			(layers "F.Cu" "F.Mask" "F.Paste")
			(net "GND")
		)
	)
	(footprint ""
		(layer "F.Cu")
		(at 359.49509 -391.0584 180)
		(property "Reference" "R1017"
			(at 0 0 180)
			(layer "F.SilkS")
			(hide yes)
			(effects
				(font
					(size 1.27 1.27)
				)
			)
		)
		(property "Value" ""
			(at 0 0 180)
			(layer "F.Fab")
			(effects
				(font
					(size 1.27 1.27)
				)
			)
		)
		(duplicate_pad_numbers_are_jumpers no)
		(fp_line
			(start 0.32512 0.175006)
			(end -0.32512 0.175006)
			(stroke
				(width 0.1)
				(type default)
			)
			(layer "F.Fab")
		)
		(fp_line
			(start 0.32512 -0.175006)
			(end 0.32512 0.175006)
			(stroke
				(width 0.1)
				(type default)
			)
			(layer "F.Fab")
		)
		(fp_line
			(start -0.32512 0.175006)
			(end -0.32512 -0.175006)
			(stroke
				(width 0.1)
				(type default)
			)
			(layer "F.Fab")
		)
		(fp_line
			(start -0.32512 -0.175006)
			(end 0.32512 -0.175006)
			(stroke
				(width 0.1)
				(type default)
			)
			(layer "F.Fab")
		)
		(pad "1" smd rect
			(at -0.2667 0 180)
			(size 0.3048 0.381)
			(layers "F.Cu" "F.Mask" "F.Paste")
			(net "P1V8_CPU0_RT_1D")
		)
		(pad "2" smd rect
			(at 0.2667 0)
			(size 0.3048 0.381)
			(layers "F.Cu" "F.Mask" "F.Paste")
			(net "RT_CPU0_P1_ADDR1")
		)
	)
)
